(kicad_pcb
	(version 20260206)
	(generator "pcbnew")
	(generator_version "10.0")
	(general
		(thickness 1.6)
		(legacy_teardrops no)
	)
	(paper "A4")
	(title_block
		(title "03242023_DA0F0TMBIJ0_F0T_Motherboard_J_brd_V01_OCP.brd")
		(comment 1 "Grand Teton / footprints 5756-5761 of 6105")
	)
	(layers
		(0 "F.Cu" signal "TOP")
		(4 "In1.Cu" signal "GND")
		(6 "In2.Cu" signal "IN1")
		(8 "In3.Cu" signal "GND1")
		(10 "In4.Cu" signal "IN2")
		(12 "In5.Cu" signal "GND2")
		(14 "In6.Cu" signal "IN3")
		(16 "In7.Cu" signal "GND3")
		(18 "In8.Cu" signal "VCC")
		(20 "In9.Cu" signal "VCC1")
		(22 "In10.Cu" signal "GND4")
		(24 "In11.Cu" signal "IN4")
		(26 "In12.Cu" signal "GND5")
		(28 "In13.Cu" signal "IN5")
		(30 "In14.Cu" signal "GND6")
		(32 "In15.Cu" signal "IN6")
		(34 "In16.Cu" signal "GND7")
		(2 "B.Cu" signal "BOTTOM")
		(9 "F.Adhes" user "F.Adhesive")
		(11 "B.Adhes" user "B.Adhesive")
		(13 "F.Paste" user "Package Geometry/Pastemask Top")
		(15 "B.Paste" user "Package Geometry/Pastemask Bottom")
		(5 "F.SilkS" user "Ref Des/Silkscreen Top")
		(7 "B.SilkS" user "Ref Des/Silkscreen Bottom")
		(1 "F.Mask" user "Board Geometry/Soldermask Top")
		(3 "B.Mask" user "Board Geometry/Soldermask Bottom")
		(17 "Dwgs.User" user "User.Drawings")
		(19 "Cmts.User" user "User.Comments")
		(21 "Eco1.User" user "User.Eco1")
		(23 "Eco2.User" user "User.Eco2")
		(25 "Edge.Cuts" user "Board Geometry/Outline")
		(27 "Margin" user)
		(31 "F.CrtYd" user "Package Geometry/Place Bound Top")
		(29 "B.CrtYd" user "Package Geometry/Place Bound Bottom")
		(35 "F.Fab" user "Ref Des/Assembly Top")
		(33 "B.Fab" user "Ref Des/Assembly Bottom")
	)
	(footprint ""
		(layer "B.Cu")
		(at 15.696946 -319.268856 180)
		(property "Reference" "C96"
			(at 0 0 0)
			(layer "B.SilkS")
			(hide yes)
			(effects
				(font
					(size 1.27 1.27)
				)
				(justify mirror)
			)
		)
		(property "Value" ""
			(at 0 0 0)
			(layer "B.Fab")
			(effects
				(font
					(size 1.27 1.27)
				)
				(justify mirror)
			)
		)
		(duplicate_pad_numbers_are_jumpers no)
		(fp_line
			(start 0.7874 0.4064)
			(end 0.7874 -0.4064)
			(stroke
				(width 0.1524)
				(type default)
			)
			(layer "B.SilkS")
		)
		(fp_line
			(start 0.7874 -0.4064)
			(end -0.7874 -0.4064)
			(stroke
				(width 0.1524)
				(type default)
			)
			(layer "B.SilkS")
		)
		(fp_line
			(start -0.7874 0.4064)
			(end 0.7874 0.4064)
			(stroke
				(width 0.1524)
				(type default)
			)
			(layer "B.SilkS")
		)
		(fp_line
			(start -0.7874 -0.4064)
			(end -0.7874 0.4064)
			(stroke
				(width 0.1524)
				(type default)
			)
			(layer "B.SilkS")
		)
		(fp_line
			(start 0.67945 0.3048)
			(end 0.67945 -0.305054)
			(stroke
				(width 0.1)
				(type default)
			)
			(layer "B.Fab")
		)
		(fp_line
			(start 0.67945 -0.305054)
			(end 0.12065 -0.305054)
			(stroke
				(width 0.1)
				(type default)
			)
			(layer "B.Fab")
		)
		(fp_line
			(start 0.12065 0.3048)
			(end 0.67945 0.3048)
			(stroke
				(width 0.1)
				(type default)
			)
			(layer "B.Fab")
		)
		(fp_line
			(start 0.12065 0.2794)
			(end 0.12065 0.3048)
			(stroke
				(width 0.1)
				(type default)
			)
			(layer "B.Fab")
		)
		(fp_line
			(start 0.12065 -0.2794)
			(end -0.12065 -0.2794)
			(stroke
				(width 0.1)
				(type default)
			)
			(layer "B.Fab")
		)
		(fp_line
			(start 0.12065 -0.305054)
			(end 0.12065 -0.2794)
			(stroke
				(width 0.1)
				(type default)
			)
			(layer "B.Fab")
		)
		(fp_line
			(start -0.120396 0.3048)
			(end -0.120396 0.2794)
			(stroke
				(width 0.1)
				(type default)
			)
			(layer "B.Fab")
		)
		(fp_line
			(start -0.120396 0.2794)
			(end 0.12065 0.2794)
			(stroke
				(width 0.1)
				(type default)
			)
			(layer "B.Fab")
		)
		(fp_line
			(start -0.12065 -0.2794)
			(end -0.12065 -0.3048)
			(stroke
				(width 0.1)
				(type default)
			)
			(layer "B.Fab")
		)
		(fp_line
			(start -0.12065 -0.3048)
			(end -0.67945 -0.3048)
			(stroke
				(width 0.1)
				(type default)
			)
			(layer "B.Fab")
		)
		(fp_line
			(start -0.67945 0.3048)
			(end -0.120396 0.3048)
			(stroke
				(width 0.1)
				(type default)
			)
			(layer "B.Fab")
		)
		(fp_line
			(start -0.67945 -0.3048)
			(end -0.67945 0.3048)
			(stroke
				(width 0.1)
				(type default)
			)
			(layer "B.Fab")
		)
		(pad "1" smd circle
			(at 0.40005 0)
			(size 0 0)
			(layers "B.Cu" "B.Mask" "B.Paste")
			(net "P3V3_AUX")
		)
		(pad "2" smd circle
			(at -0.40005 0)
			(size 0 0)
			(layers "B.Cu" "B.Mask" "B.Paste")
			(net "GND")
		)
	)
	(footprint ""
		(layer "B.Cu")
		(at 372.675912 -333.73568 90)
		(property "Reference" "PC280_P0_4"
			(at 0 0 90)
			(layer "B.SilkS")
			(hide yes)
			(effects
				(font
					(size 1.27 1.27)
				)
				(justify mirror)
			)
		)
		(property "Value" ""
			(at 0 0 90)
			(layer "B.Fab")
			(effects
				(font
					(size 1.27 1.27)
				)
				(justify mirror)
			)
		)
		(duplicate_pad_numbers_are_jumpers no)
		(fp_line
			(start 1.524 -0.762)
			(end -1.524 -0.762)
			(stroke
				(width 0.1524)
				(type default)
			)
			(layer "B.SilkS")
		)
		(fp_line
			(start -1.524 -0.762)
			(end -1.524 0.762)
			(stroke
				(width 0.1524)
				(type default)
			)
			(layer "B.SilkS")
		)
		(fp_line
			(start 1.524 0.762)
			(end 1.524 -0.762)
			(stroke
				(width 0.1524)
				(type default)
			)
			(layer "B.SilkS")
		)
		(fp_line
			(start -1.524 0.762)
			(end 1.524 0.762)
			(stroke
				(width 0.1524)
				(type default)
			)
			(layer "B.SilkS")
		)
		(fp_line
			(start 1.1049 -0.724916)
			(end 1.1049 0.724916)
			(stroke
				(width 0.1)
				(type default)
			)
			(layer "B.Fab")
		)
		(fp_line
			(start -1.1049 -0.724916)
			(end 1.1049 -0.724916)
			(stroke
				(width 0.1)
				(type default)
			)
			(layer "B.Fab")
		)
		(fp_line
			(start 1.1049 0.724916)
			(end -1.1049 0.724916)
			(stroke
				(width 0.1)
				(type default)
			)
			(layer "B.Fab")
		)
		(fp_line
			(start -1.1049 0.724916)
			(end -1.1049 -0.724916)
			(stroke
				(width 0.1)
				(type default)
			)
			(layer "B.Fab")
		)
		(pad "1" smd rect
			(at 0.889 0 90)
			(size 1.016 1.27)
			(layers "B.Cu" "B.Mask" "B.Paste")
			(net "SW_P12V_PVCCIN_CPU0_FLT")
		)
		(pad "2" smd rect
			(at -0.889 0 90)
			(size 1.016 1.27)
			(layers "B.Cu" "B.Mask" "B.Paste")
			(net "GND")
		)
	)
	(footprint ""
		(layer "B.Cu")
		(at 38.420548 -392.686286 180)
		(property "Reference" "C1866"
			(at 0 0 0)
			(layer "B.SilkS")
			(hide yes)
			(effects
				(font
					(size 1.27 1.27)
				)
				(justify mirror)
			)
		)
		(property "Value" ""
			(at 0 0 0)
			(layer "B.Fab")
			(effects
				(font
					(size 1.27 1.27)
				)
				(justify mirror)
			)
		)
		(duplicate_pad_numbers_are_jumpers no)
		(fp_line
			(start 0.7874 0.4064)
			(end 0.7874 -0.4064)
			(stroke
				(width 0.1524)
				(type default)
			)
			(layer "B.SilkS")
		)
		(fp_line
			(start 0.7874 -0.4064)
			(end -0.7874 -0.4064)
			(stroke
				(width 0.1524)
				(type default)
			)
			(layer "B.SilkS")
		)
		(fp_line
			(start -0.7874 0.4064)
			(end 0.7874 0.4064)
			(stroke
				(width 0.1524)
				(type default)
			)
			(layer "B.SilkS")
		)
		(fp_line
			(start -0.7874 -0.4064)
			(end -0.7874 0.4064)
			(stroke
				(width 0.1524)
				(type default)
			)
			(layer "B.SilkS")
		)
		(fp_line
			(start 0.67945 0.3048)
			(end 0.67945 -0.305054)
			(stroke
				(width 0.1)
				(type default)
			)
			(layer "B.Fab")
		)
		(fp_line
			(start 0.67945 -0.305054)
			(end 0.12065 -0.305054)
			(stroke
				(width 0.1)
				(type default)
			)
			(layer "B.Fab")
		)
		(fp_line
			(start 0.12065 0.3048)
			(end 0.67945 0.3048)
			(stroke
				(width 0.1)
				(type default)
			)
			(layer "B.Fab")
		)
		(fp_line
			(start 0.12065 0.2794)
			(end 0.12065 0.3048)
			(stroke
				(width 0.1)
				(type default)
			)
			(layer "B.Fab")
		)
		(fp_line
			(start 0.12065 -0.2794)
			(end -0.12065 -0.2794)
			(stroke
				(width 0.1)
				(type default)
			)
			(layer "B.Fab")
		)
		(fp_line
			(start 0.12065 -0.305054)
			(end 0.12065 -0.2794)
			(stroke
				(width 0.1)
				(type default)
			)
			(layer "B.Fab")
		)
		(fp_line
			(start -0.120396 0.3048)
			(end -0.120396 0.2794)
			(stroke
				(width 0.1)
				(type default)
			)
			(layer "B.Fab")
		)
		(fp_line
			(start -0.120396 0.2794)
			(end 0.12065 0.2794)
			(stroke
				(width 0.1)
				(type default)
			)
			(layer "B.Fab")
		)
		(fp_line
			(start -0.12065 -0.2794)
			(end -0.12065 -0.3048)
			(stroke
				(width 0.1)
				(type default)
			)
			(layer "B.Fab")
		)
		(fp_line
			(start -0.12065 -0.3048)
			(end -0.67945 -0.3048)
			(stroke
				(width 0.1)
				(type default)
			)
			(layer "B.Fab")
		)
		(fp_line
			(start -0.67945 0.3048)
			(end -0.120396 0.3048)
			(stroke
				(width 0.1)
				(type default)
			)
			(layer "B.Fab")
		)
		(fp_line
			(start -0.67945 -0.3048)
			(end -0.67945 0.3048)
			(stroke
				(width 0.1)
				(type default)
			)
			(layer "B.Fab")
		)
		(pad "1" smd circle
			(at 0.40005 0)
			(size 0 0)
			(layers "B.Cu" "B.Mask" "B.Paste")
			(net "P3V3_AUX")
		)
		(pad "2" smd circle
			(at -0.40005 0)
			(size 0 0)
			(layers "B.Cu" "B.Mask" "B.Paste")
			(net "GND")
		)
	)
	(footprint ""
		(layer "B.Cu")
		(at 369.769898 -359.586276 -90)
		(property "Reference" "PJ65"
			(at -4.651502 -2.444242 0)
			(unlocked yes)
			(layer "B.SilkS")
			(effects
				(font
					(size 0.7874 0.5842)
					(thickness 0.1524)
				)
				(justify left mirror)
			)
		)
		(property "Value" ""
			(at 0 0 90)
			(layer "B.Fab")
			(effects
				(font
					(size 1.27 1.27)
				)
				(justify mirror)
			)
		)
		(duplicate_pad_numbers_are_jumpers no)
		(pad "1" smd circle
			(at 0.7493 0)
			(size 0 0)
			(layers "B.Cu" "B.Mask" "B.Paste")
			(net "SH_PVPP_HBM_CPU0_N")
		)
		(pad "2" smd rect
			(at -0.7493 0 180)
			(size 0.7112 0.8128)
			(layers "B.Cu" "B.Mask" "B.Paste")
			(net "GND")
		)
		(zone
			(layer "B.Cu")
			(hatch none 0.5)
			(connect_pads
				(clearance 0)
			)
			(min_thickness 0.25)
			(keepout
				(tracks allowed)
				(vias not_allowed)
				(pads allowed)
				(copperpour not_allowed)
				(footprints allowed)
			)
			(placement
				(enabled no)
				(sheetname "")
			)
			(fill
				(thermal_gap 0.5)
				(thermal_bridge_width 0.5)
				(island_removal_mode 0)
			)
			(polygon
				(pts
					(xy 369.358672 -358.405176) (xy 370.176298 -358.405176) (xy 370.176298 -360.792776) (xy 369.358672 -360.792776)
				)
			)
		)
	)
	(footprint ""
		(layer "B.Cu")
		(at 52.15128 -171.541948 -90)
		(property "Reference" "PR678"
			(at 0 0 90)
			(layer "B.SilkS")
			(hide yes)
			(effects
				(font
					(size 1.27 1.27)
				)
				(justify mirror)
			)
		)
		(property "Value" ""
			(at 0 0 90)
			(layer "B.Fab")
			(effects
				(font
					(size 1.27 1.27)
				)
				(justify mirror)
			)
		)
		(duplicate_pad_numbers_are_jumpers no)
		(fp_line
			(start -0.7874 0.4064)
			(end 0.7874 0.4064)
			(stroke
				(width 0.1524)
				(type default)
			)
			(layer "B.SilkS")
		)
		(fp_line
			(start 0.7874 0.4064)
			(end 0.7874 -0.4064)
			(stroke
				(width 0.1524)
				(type default)
			)
			(layer "B.SilkS")
		)
		(fp_line
			(start -0.7874 -0.4064)
			(end -0.7874 0.4064)
			(stroke
				(width 0.1524)
				(type default)
			)
			(layer "B.SilkS")
		)
		(fp_line
			(start 0.7874 -0.4064)
			(end -0.7874 -0.4064)
			(stroke
				(width 0.1524)
				(type default)
			)
			(layer "B.SilkS")
		)
		(fp_line
			(start -0.67945 0.3048)
			(end -0.120396 0.3048)
			(stroke
				(width 0.1)
				(type default)
			)
			(layer "B.Fab")
		)
		(fp_line
			(start -0.120396 0.3048)
			(end -0.120396 0.2794)
			(stroke
				(width 0.1)
				(type default)
			)
			(layer "B.Fab")
		)
		(fp_line
			(start 0.12065 0.3048)
			(end 0.67945 0.3048)
			(stroke
				(width 0.1)
				(type default)
			)
			(layer "B.Fab")
		)
		(fp_line
			(start 0.67945 0.3048)
			(end 0.67945 -0.305054)
			(stroke
				(width 0.1)
				(type default)
			)
			(layer "B.Fab")
		)
		(fp_line
			(start -0.120396 0.2794)
			(end 0.12065 0.2794)
			(stroke
				(width 0.1)
				(type default)
			)
			(layer "B.Fab")
		)
		(fp_line
			(start 0.12065 0.2794)
			(end 0.12065 0.3048)
			(stroke
				(width 0.1)
				(type default)
			)
			(layer "B.Fab")
		)
		(fp_line
			(start -0.12065 -0.2794)
			(end -0.12065 -0.3048)
			(stroke
				(width 0.1)
				(type default)
			)
			(layer "B.Fab")
		)
		(fp_line
			(start 0.12065 -0.2794)
			(end -0.12065 -0.2794)
			(stroke
				(width 0.1)
				(type default)
			)
			(layer "B.Fab")
		)
		(fp_line
			(start -0.67945 -0.3048)
			(end -0.67945 0.3048)
			(stroke
				(width 0.1)
				(type default)
			)
			(layer "B.Fab")
		)
		(fp_line
			(start -0.12065 -0.3048)
			(end -0.67945 -0.3048)
			(stroke
				(width 0.1)
				(type default)
			)
			(layer "B.Fab")
		)
		(fp_line
			(start 0.12065 -0.305054)
			(end 0.12065 -0.2794)
			(stroke
				(width 0.1)
				(type default)
			)
			(layer "B.Fab")
		)
		(fp_line
			(start 0.67945 -0.305054)
			(end 0.12065 -0.305054)
			(stroke
				(width 0.1)
				(type default)
			)
			(layer "B.Fab")
		)
		(pad "1" smd circle
			(at 0.40005 0 90)
			(size 0 0)
			(layers "B.Cu" "B.Mask" "B.Paste")
			(net "P5V")
		)
		(pad "2" smd circle
			(at -0.40005 0 90)
			(size 0 0)
			(layers "B.Cu" "B.Mask" "B.Paste")
			(net "PVCCFA_EHV_CPU1_PVCC")
		)
	)
	(footprint ""
		(layer "B.Cu")
		(at 61.62421 -156.47797)
		(property "Reference" "PC1594"
			(at 0 0 0)
			(layer "B.SilkS")
			(hide yes)
			(effects
				(font
					(size 1.27 1.27)
				)
				(justify mirror)
			)
		)
		(property "Value" ""
			(at 0 0 0)
			(layer "B.Fab")
			(effects
				(font
					(size 1.27 1.27)
				)
				(justify mirror)
			)
		)
		(duplicate_pad_numbers_are_jumpers no)
		(fp_line
			(start -4.53898 -2.15011)
			(end -4.53898 2.15011)
			(stroke
				(width 0.1524)
				(type default)
			)
			(layer "B.SilkS")
		)
		(fp_line
			(start -4.53898 2.15011)
			(end 4.53898 2.15011)
			(stroke
				(width 0.1524)
				(type default)
			)
			(layer "B.SilkS")
		)
		(fp_line
			(start 4.53898 -2.150618)
			(end 4.539742 2.152142)
			(stroke
				(width 0.1524)
				(type default)
			)
			(layer "B.SilkS")
		)
		(fp_line
			(start 4.53898 -2.15011)
			(end -4.53898 -2.15011)
			(stroke
				(width 0.1524)
				(type default)
			)
			(layer "B.SilkS")
		)
		(fp_line
			(start 4.53898 2.15011)
			(end 4.53898 -2.15011)
			(stroke
				(width 0.1524)
				(type default)
			)
			(layer "B.SilkS")
		)
		(fp_line
			(start 4.69138 -2.150618)
			(end 4.692396 2.161032)
			(stroke
				(width 0.1524)
				(type default)
			)
			(layer "B.SilkS")
		)
		(fp_line
			(start 4.83108 2.150364)
			(end 4.447794 2.149348)
			(stroke
				(width 0.1524)
				(type default)
			)
			(layer "B.SilkS")
		)
		(fp_line
			(start 4.84378 -2.150618)
			(end 4.53898 -2.150618)
			(stroke
				(width 0.1524)
				(type default)
			)
			(layer "B.SilkS")
		)
		(fp_line
			(start 4.84378 -2.150618)
			(end 4.842256 2.163064)
			(stroke
				(width 0.1524)
				(type default)
			)
			(layer "B.SilkS")
		)
		(fp_line
			(start -3.64998 -2.15011)
			(end -3.64998 2.15011)
			(stroke
				(width 0.1)
				(type default)
			)
			(layer "B.Fab")
		)
		(fp_line
			(start -3.64998 2.15011)
			(end 3.64998 2.15011)
			(stroke
				(width 0.1)
				(type default)
			)
			(layer "B.Fab")
		)
		(fp_line
			(start 3.64998 -2.15011)
			(end -3.64998 -2.15011)
			(stroke
				(width 0.1)
				(type default)
			)
			(layer "B.Fab")
		)
		(fp_line
			(start 3.64998 2.15011)
			(end 3.64998 -2.15011)
			(stroke
				(width 0.1)
				(type default)
			)
			(layer "B.Fab")
		)
		(fp_text user "-"
			(at -4.79425 0.764032 0)
			(unlocked yes)
			(layer "B.SilkS")
			(effects
				(font
					(size 1.905 1.4224)
					(thickness 0.1524)
				)
				(justify left mirror)
			)
		)
		(fp_text user "+"
			(at 6.214872 -0.337058 0)
			(unlocked yes)
			(layer "B.SilkS")
			(effects
				(font
					(size 1.905 1.4224)
					(thickness 0.1524)
				)
				(justify left mirror)
			)
		)
		(fp_text user "-"
			(at -4.313174 -0.094488 0)
			(unlocked yes)
			(layer "B.Fab")
			(effects
				(font
					(size 1.905 1.4224)
					(thickness 0.1524)
				)
				(justify left mirror)
			)
		)
		(fp_text user "+"
			(at 6.214872 -0.337058 0)
			(unlocked yes)
			(layer "B.Fab")
			(effects
				(font
					(size 1.905 1.4224)
					(thickness 0.1524)
				)
				(justify left mirror)
			)
		)
		(pad "1" smd rect
			(at 3.199892 0 180)
			(size 2.413 2.8194)
			(layers "B.Cu" "B.Mask" "B.Paste")
			(net "PVCCINFAON_CPU1")
		)
		(pad "2" smd rect
			(at -3.199892 0 180)
			(size 2.413 2.8194)
			(layers "B.Cu" "B.Mask" "B.Paste")
			(net "GND")
		)
	)
)
